# S9S_MB_2U (Grand Teton) — schematic parts with pin connectivity, parts 5876–5876 of 6093; source: Cadence DE-HDL packaged netlist (pstxprt.dat, pstxnet.dat, pstchip.dat)

U1  SOCKET4677_AZIF0045P001C01CS  SOCKET4677_AZIF0045-P001C01CS IO  pkg SOCKET4677_82X64-5XA_H466  page 44  (pins 1309-1635 of 4677)
  BN56  VCCIN46  POWER  = PVCCIN_CPU1
  BN58  VCCIN47  POWER  = PVCCIN_CPU1
  BN60  VCCIN48  POWER  = PVCCIN_CPU1
  BN62  VSS519  POWER  = GND
  BN64  PKG_ID2  IN  = FM_CPU1_PKGID2
  BN66  PTI_DIE0115  OUT  = TP_TRC_CPU1_PTI<31>
  BN68  PTI_DIE0110  OUT  = TP_TRC_CPU1_PTI<26>
  BN70  VSS520  POWER  = GND
  BN72  UPI2_TX_DP23  OUT  = UPI_CPU1_CPU0_P2P2_DP<23>
  BN74  UPI2_RX_DN21  IN  = UPI_CPU0_CPU1_P2P2_DN<21>
  BN76  UPI2_RX_DP19  IN  = UPI_CPU0_CPU1_P2P2_DP<19>
  BN78  VCCIN49  POWER  = PVCCIN_CPU1
  BN80  VCCIN50  POWER  = PVCCIN_CPU1
  BN82  VCCIN51  POWER  = PVCCIN_CPU1
  BN84  VCCIN52  POWER  = PVCCIN_CPU1
  BN86  VCCIN53  POWER  = PVCCIN_CPU1
  BN88  VCCIN54  POWER  = PVCCIN_CPU1
  BN90  VCCIN55  POWER  = PVCCIN_CPU1
  BP2  VSS524  POWER  = GND
  BP4  VSS527  POWER  = GND
  BP6  UPI0_RX_DP22  IN  = UPI_CPU0_CPU1_P1P0_DP<22>
  BP8  VSS533  POWER  = GND
  BP10  PE1_RX_DN10  IN  = P5E_CPU1_PE1_RX_DN<10>
  BP12  VSS522  POWER  = GND
  BP14  PE1_TX_DN10  OUT  = P5E_CPU1_PE1_TX_DN<10>
  BP16  VSS523  POWER  = GND
  BP18  DMI_RX_DN6  IN  = TP_DMI_CPU1_PCH_RX_C_DN<6>
  BP20  VSS525  POWER  = GND
  BP22  RSVD67  BI  = NC_CPU1_MDFI_DIE00_EW0
  BP24  CATERR_N  BI  = H_CPU1_CATERR_LVC1_R_N
  BP26  PRDY_N  OUT  = H_CPU1_PRDY_QS_GTL_R_N
  BP28  PTI_DIE0013  OUT  = TP_TRC_CPU1_PTI<13>
  BP30  PTI_DIE0015  OUT  = TP_TRC_CPU1_PTI<15>
  BP32  VCCIN56  POWER  = PVCCIN_CPU1
  BP34  VCCIN57  POWER  = PVCCIN_CPU1
  BP36  VCCIN58  POWER  = PVCCIN_CPU1
  BP38  VCCIN59  POWER  = PVCCIN_CPU1
  BP40  VCCIN60  POWER  = PVCCIN_CPU1
  BP42  VCCIN61  POWER  = PVCCIN_CPU1
  BP44  VCCIN62  POWER  = PVCCIN_CPU1
  BP47  VCCIN63  POWER  = PVCCIN_CPU1
  BP49  VCCIN64  POWER  = PVCCIN_CPU1
  BP51  VCCIN65  POWER  = PVCCIN_CPU1
  BP53  VCCIN66  POWER  = PVCCIN_CPU1
  BP55  VCCIN67  POWER  = PVCCIN_CPU1
  BP57  VCCIN68  POWER  = PVCCIN_CPU1
  BP59  VCCIN69  POWER  = PVCCIN_CPU1
  BP61  VCCIN70  POWER  = PVCCIN_CPU1
  BP63  VSS528  POWER  = GND
  BP65  RSVD68  BI  = NC_CPU1_SOC_SPARE5
  BP67  RSVD69  BI  = CPU1_RSVD<64>
  BP69  RSVD70  BI  = CPU1_RSVD<65>
  BP71  VSS529  POWER  = GND
  BP73  VSS530  POWER  = GND
  BP75  VSS531  POWER  = GND
  BP77  VSS532  POWER  = GND
  BP79  VCCIN71  POWER  = PVCCIN_CPU1
  BP81  VCCIN72  POWER  = PVCCIN_CPU1
  BP83  VCCIN73  POWER  = PVCCIN_CPU1
  BP85  VCCIN74  POWER  = PVCCIN_CPU1
  BP87  VCCIN75  POWER  = PVCCIN_CPU1
  BP89  VCCIN76  POWER  = PVCCIN_CPU1
  BR3  UPI0_TX_DN22  OUT  = UPI_CPU1_CPU0_P0P1_DN<22>
  BR5  VSS0  POWER  = GND
  BR7  UPI0_RX_DN22  IN  = UPI_CPU0_CPU1_P1P0_DN<22>
  BR9  VSS572  POWER  = GND
  BR11  PE1_RX_DN9  IN  = P5E_CPU1_PE1_RX_DN<9>
  BR13  VSS535  POWER  = GND
  BR15  PE1_TX_DP10  OUT  = P5E_CPU1_PE1_TX_DP<10>
  BR17  VSS536  POWER  = GND
  BR19  DMI_RX_DP6  IN  = TP_DMI_CPU1_PCH_RX_C_DP<6>
  BR21  RSVD71  BI  = NC_CPU1_MDFI_DIE00_EW1
  BR23  RSVD72  BI  = TP_CPU1_BR23
  BR25  TMS  IN  = JTAG_DBP_CPU1_QS_GTL_R_TMS
  BR27  VSS538  POWER  = GND
  BR29  VSS539  POWER  = GND
  BR31  VSS540  POWER  = GND
  BR33  VSS541  POWER  = GND
  BR35  VSS542  POWER  = GND
  BR37  VSS543  POWER  = GND
  BR39  VSS545  POWER  = GND
  BR41  VSS546  POWER  = GND
  BR43  VSS547  POWER  = GND
  BR45  VSS548  POWER  = GND
  BR48  VSS549  POWER  = GND
  BR50  VSS550  POWER  = GND
  BR52  VSS551  POWER  = GND
  BR54  VSS552  POWER  = GND
  BR56  VSS555  POWER  = GND
  BR58  VSS556  POWER  = GND
  BR60  VCCIN77  POWER  = PVCCIN_CPU1
  BR62  VCCIN78  POWER  = PVCCIN_CPU1
  BR64  VSS557  POWER  = GND
  BR66  VSS559  POWER  = GND
  BR68  VSS560  POWER  = GND
  BR70  VSS561  POWER  = GND
  BR72  VSS563  POWER  = GND
  BR74  VSS564  POWER  = GND
  BR76  VSS565  POWER  = GND
  BR78  VCCIN79  POWER  = PVCCIN_CPU1
  BR80  VSS566  POWER  = GND
  BR82  VSS567  POWER  = GND
  BR84  VSS568  POWER  = GND
  BR86  VSS569  POWER  = GND
  BR88  VSS570  POWER  = GND
  BR90  VSS573  POWER  = GND
  BT2  UPI0_TX_DN23  OUT  = UPI_CPU1_CPU0_P0P1_DN<23>
  BT4  VSS577  POWER  = GND
  BT6  UPI0_RX_DP23  IN  = UPI_CPU0_CPU1_P1P0_DP<23>
  BT8  VSS578  POWER  = GND
  BT10  PE1_RX_DP9  IN  = P5E_CPU1_PE1_RX_DP<9>
  BT12  VSS574  POWER  = GND
  BT14  PE1_TX_DP9  OUT  = P5E_CPU1_PE1_TX_DP<9>
  BT16  VSS575  POWER  = GND
  BT18  DMI_RX_DP7  IN  = TP_DMI_CPU1_PCH_RX_C_DP<7>
  BT20  VSS576  POWER  = GND
  BT22  DDR0123_SPDSCL  OUT  = I3C_SPD_DDRABCD_CPU1_SCL
  BT24  TCK  IN  = JTAG_DBP_CPU1_GTL_R_TCK
  BT26  TXT_AGENT  IN  = PU_CPU1_TXT_AGENT
  BT28  PTI_DIE009  OUT  = TP_TRC_CPU1_PTI<9>
  BT30  PTI_DIE0011  OUT  = TP_TRC_CPU1_PTI<11>
  BT32  VCCIN80  POWER  = PVCCIN_CPU1
  BT34  VCCIN81  POWER  = PVCCIN_CPU1
  BT36  VCCIN82  POWER  = PVCCIN_CPU1
  BT38  VCCIN83  POWER  = PVCCIN_CPU1
  BT40  VCCIN84  POWER  = PVCCIN_CPU1
  BT42  VCCIN85  POWER  = PVCCIN_CPU1
  BT44  VCCIN86  POWER  = PVCCIN_CPU1
  BT47  VCCIN87  POWER  = PVCCIN_CPU1
  BT49  VCCIN88  POWER  = PVCCIN_CPU1
  BT51  VCCIN89  POWER  = PVCCIN_CPU1
  BT53  VCCIN90  POWER  = PVCCIN_CPU1
  BT55  VCCIN91  POWER  = PVCCIN_CPU1
  BT57  VCCIN92  POWER  = PVCCIN_CPU1
  BT59  VCCIN93  POWER  = PVCCIN_CPU1
  BT61  VCCIN94  POWER  = PVCCIN_CPU1
  BT63  VCCIN95  POWER  = PVCCIN_CPU1
  BT65  VCCIN96  POWER  = PVCCIN_CPU1
  BT67  VCCIN97  POWER  = PVCCIN_CPU1
  BT69  VCCIN98  POWER  = PVCCIN_CPU1
  BT71  VCCIN99  POWER  = PVCCIN_CPU1
  BT73  VCCIN100  POWER  = PVCCIN_CPU1
  BT75  VCCIN101  POWER  = PVCCIN_CPU1
  BT77  VCCIN102  POWER  = PVCCIN_CPU1
  BT79  VCCIN103  POWER  = PVCCIN_CPU1
  BT81  VCCIN104  POWER  = PVCCIN_CPU1
  BT83  VCCIN105  POWER  = PVCCIN_CPU1
  BT85  VCCIN106  POWER  = PVCCIN_CPU1
  BT87  VCCIN107  POWER  = PVCCIN_CPU1
  BT89  VCCIN108  POWER  = PVCCIN_CPU1
  BU3  UPI0_TX_DP23  OUT  = UPI_CPU1_CPU0_P0P1_DP<23>
  BU5  UPI0_RX_DN23  IN  = UPI_CPU0_CPU1_P1P0_DN<23>
  BU7  VSS586  POWER  = GND
  BU9  PE1_RX_DP8  IN  = P5E_CPU1_PE1_RX_DP<8>
  BU11  VCCD_HV_SENSE  POWER  = VSENSE_PVCCD_HV_CPU1_DP
  BU13  PE1_TX_DN9  OUT  = P5E_CPU1_PE1_TX_DN<9>
  BU15  VSS579  POWER  = GND
  BU17  DMI_RX_DN7  IN  = TP_DMI_CPU1_PCH_RX_C_DN<7>
  BU19  VSS580  POWER  = GND
  BU21  VSS581  POWER  = GND
  BU23  VSS582  POWER  = GND
  BU25  VSS584  POWER  = GND
  BU27  PTI_DIE008  OUT  = TP_TRC_CPU1_PTI<8>
  BU29  PTI_DIE0010  OUT  = TP_TRC_CPU1_PTI<10>
  BU31  VSS585  POWER  = GND
  BU33  VCCIN109  POWER  = PVCCIN_CPU1
  BU35  VCCIN110  POWER  = PVCCIN_CPU1
  BU37  VCCIN111  POWER  = PVCCIN_CPU1
  BU39  VCCIN112  POWER  = PVCCIN_CPU1
  BU41  VCCIN113  POWER  = PVCCIN_CPU1
  BU43  VCCIN114  POWER  = PVCCIN_CPU1
  BU45  VCCIN115  POWER  = PVCCIN_CPU1
  BU48  VCCIN116  POWER  = PVCCIN_CPU1
  BU50  VCCIN117  POWER  = PVCCIN_CPU1
  BU52  VCCIN118  POWER  = PVCCIN_CPU1
  BU54  VCCIN119  POWER  = PVCCIN_CPU1
  BU56  VCCIN120  POWER  = PVCCIN_CPU1
  BU58  VCCIN121  POWER  = PVCCIN_CPU1
  BU60  VCCIN122  POWER  = PVCCIN_CPU1
  BU62  VCCIN123  POWER  = PVCCIN_CPU1
  BU64  VCCIN124  POWER  = PVCCIN_CPU1
  BU66  VCCIN125  POWER  = PVCCIN_CPU1
  BU68  VCCIN126  POWER  = PVCCIN_CPU1
  BU70  VCCIN127  POWER  = PVCCIN_CPU1
  BU72  VCCIN128  POWER  = PVCCIN_CPU1
  BU74  VCCIN129  POWER  = PVCCIN_CPU1
  BU76  VCCIN130  POWER  = PVCCIN_CPU1
  BU78  VCCIN131  POWER  = PVCCIN_CPU1
  BU80  VCCIN132  POWER  = PVCCIN_CPU1
  BU82  VCCIN133  POWER  = PVCCIN_CPU1
  BU84  VCCIN134  POWER  = PVCCIN_CPU1
  BU86  VCCIN135  POWER  = PVCCIN_CPU1
  BU88  VCCIN136  POWER  = PVCCIN_CPU1
  BU90  VCCIN137  POWER  = PVCCIN_CPU1
  BV2  VSS590  POWER  = GND
  BV4  VSS592  POWER  = GND
  BV6  VSS593  POWER  = GND
  BV8  VSS594  POWER  = GND
  BV10  PE1_RX_DN8  IN  = P5E_CPU1_PE1_RX_DN<8>
  BV12  VSS587  POWER  = GND
  BV14  PE1_TX_DN8  OUT  = P5E_CPU1_PE1_TX_DN<8>
  BV16  VSS588  POWER  = GND
  BV18  VSS589  POWER  = GND
  BV20  VSS591  POWER  = GND
  BV22  RSVD73  BI  = NC_CPU1_UPI1_APROBE<0>
  BV24  TDI  IN  = JTAG_DBP_CPU1_GTL_R_TDI
  BV26  CXPSMBUS_ALERT_N  IN  = FM_PEHPCPU1_ALERT_N
  BV28  PTI_DIE007  OUT  = TP_TRC_CPU1_PTI<7>
  BV30  PTI_DIE005  OUT  = TP_TRC_CPU1_PTI<5>
  BV32  VCCIN138  POWER  = PVCCIN_CPU1
  BV34  VCCIN139  POWER  = PVCCIN_CPU1
  BV36  VCCIN140  POWER  = PVCCIN_CPU1
  BV38  VCCIN141  POWER  = PVCCIN_CPU1
  BV40  VCCIN142  POWER  = PVCCIN_CPU1
  BV42  VCCIN143  POWER  = PVCCIN_CPU1
  BV44  VCCIN144  POWER  = PVCCIN_CPU1
  BV47  VCCIN145  POWER  = PVCCIN_CPU1
  BV49  VCCIN146  POWER  = PVCCIN_CPU1
  BV51  VCCIN147  POWER  = PVCCIN_CPU1
  BV53  VCCIN148  POWER  = PVCCIN_CPU1
  BV55  VCCIN149  POWER  = PVCCIN_CPU1
  BV57  VCCIN150  POWER  = PVCCIN_CPU1
  BV59  VCCIN151  POWER  = PVCCIN_CPU1
  BV61  VCCIN152  POWER  = PVCCIN_CPU1
  BV63  VCCIN153  POWER  = PVCCIN_CPU1
  BV65  VCCIN154  POWER  = PVCCIN_CPU1
  BV67  VCCIN155  POWER  = PVCCIN_CPU1
  BV69  VCCIN156  POWER  = PVCCIN_CPU1
  BV71  VCCIN157  POWER  = PVCCIN_CPU1
  BV73  VCCIN158  POWER  = PVCCIN_CPU1
  BV75  VCCIN159  POWER  = PVCCIN_CPU1
  BV77  VCCIN160  POWER  = PVCCIN_CPU1
  BV79  VCCIN161  POWER  = PVCCIN_CPU1
  BV81  VCCIN162  POWER  = PVCCIN_CPU1
  BV83  VCCIN163  POWER  = PVCCIN_CPU1
  BV85  VCCIN164  POWER  = PVCCIN_CPU1
  BV87  VCCIN165  POWER  = PVCCIN_CPU1
  BV89  VCCIN166  POWER  = PVCCIN_CPU1
  BW3  VSS600  POWER  = GND
  BW5  VSS602  POWER  = GND
  BW7  UPI1_TX_DP23  OUT  = UPI_CPU1_CPU0_P1P0_DP<23>
  BW9  VSS603  POWER  = GND
  BW11  PE1_RX_DN7  IN  = P5E_CPU1_PE1_RX_DN<7>
  BW13  VSS596  POWER  = GND
  BW15  PE1_TX_DP8  OUT  = P5E_CPU1_PE1_TX_DP<8>
  BW17  VSS597  POWER  = GND
  BW19  DMI_TX_DN0  OUT  = TP_DMI_CPU1_PCH_TX_DN<0>
  BW21  RSVD74  BI  = NC_CPU1_DMI_APROBE<1>
  BW23  RSVD75  BI  = NC_CPU1_PE2_APROBE<1>
  BW25  TDO  OUT  = JTAG_CPU1_MUX_GTL_TDO
  BW27  VSS598  POWER  = GND
  BW29  VSS599  POWER  = GND
  BW31  VSS601  POWER  = GND
  BW33  VCCIN167  POWER  = PVCCIN_CPU1
  BW35  VCCIN168  POWER  = PVCCIN_CPU1
  BW37  VCCIN169  POWER  = PVCCIN_CPU1
  BW39  VCCIN170  POWER  = PVCCIN_CPU1
  BW41  VCCIN171  POWER  = PVCCIN_CPU1
  BW43  VCCIN172  POWER  = PVCCIN_CPU1
  BW45  VCCIN173  POWER  = PVCCIN_CPU1
  BW48  VCCIN174  POWER  = PVCCIN_CPU1
  BW50  VCCIN175  POWER  = PVCCIN_CPU1
  BW52  VCCIN176  POWER  = PVCCIN_CPU1
  BW54  VCCIN177  POWER  = PVCCIN_CPU1
  BW56  VCCIN178  POWER  = PVCCIN_CPU1
  BW58  VCCIN179  POWER  = PVCCIN_CPU1
  BW60  VCCIN180  POWER  = PVCCIN_CPU1
  BW62  VCCIN181  POWER  = PVCCIN_CPU1
  BW64  VCCIN182  POWER  = PVCCIN_CPU1
  BW66  VCCIN183  POWER  = PVCCIN_CPU1
  BW68  VCCIN184  POWER  = PVCCIN_CPU1
  BW70  VCCIN185  POWER  = PVCCIN_CPU1
  BW72  VCCIN186  POWER  = PVCCIN_CPU1
  BW74  VCCIN187  POWER  = PVCCIN_CPU1
  BW76  VCCIN188  POWER  = PVCCIN_CPU1
  BW78  VCCIN189  POWER  = PVCCIN_CPU1
  BW80  VCCIN190  POWER  = PVCCIN_CPU1
  BW82  VCCIN191  POWER  = PVCCIN_CPU1
  BW84  VCCIN192  POWER  = PVCCIN_CPU1
  BW86  VCCIN193  POWER  = PVCCIN_CPU1
  BW88  VCCIN194  POWER  = PVCCIN_CPU1
  BW90  VCCIN195  POWER  = PVCCIN_CPU1
  BY2  UPI1_RX_DP23  IN  = UPI_CPU0_CPU1_P0P1_DP<23>
  BY4  VSS607  POWER  = GND
  BY6  UPI1_TX_DN23  OUT  = UPI_CPU1_CPU0_P1P0_DN<23>
  BY8  VSS608  POWER  = GND
  BY10  PE1_RX_DP7  IN  = P5E_CPU1_PE1_RX_DP<7>
  BY12  VSS604  POWER  = GND
  BY14  PE1_TX_DP7  OUT  = P5E_CPU1_PE1_TX_DP<7>
  BY16  VSS605  POWER  = GND
  BY18  DMI_TX_DP1  OUT  = TP_DMI_CPU1_PCH_TX_DP<1>
  BY20  VSS606  POWER  = GND
  BY22  DDR0123_SPDSDA  BI  = I3C_SPD_DDRABCD_CPU1_SDA
  BY24  RSVD76  BI  = PD_EXT_CLK_SEL_CPU1
  BY26  CXPSMBUSSDA  BI  = SMB_PEHPCPU1_GTL_SDA
  BY28  PTI_DIE00_STB_1  OUT  = TP_TRC_CPU1_PTI1_CLK
  BY30  PTI_DIE003  OUT  = TP_TRC_CPU1_PTI<3>
  BY32  VCCIN196  POWER  = PVCCIN_CPU1
  BY34  VCCIN197  POWER  = PVCCIN_CPU1
  BY36  VCCIN198  POWER  = PVCCIN_CPU1
  BY38  VCCIN199  POWER  = PVCCIN_CPU1
  BY40  VCCIN200  POWER  = PVCCIN_CPU1
  BY42  VCCIN201  POWER  = PVCCIN_CPU1
  BY44  VCCIN202  POWER  = PVCCIN_CPU1
  BY47  VCCIN203  POWER  = PVCCIN_CPU1
  BY49  VCCIN204  POWER  = PVCCIN_CPU1
  BY51  VCCIN205  POWER  = PVCCIN_CPU1
  BY53  VCCIN206  POWER  = PVCCIN_CPU1
  BY55  VCCIN207  POWER  = PVCCIN_CPU1
  BY57  VCCIN208  POWER  = PVCCIN_CPU1
  BY59  VCCIN209  POWER  = PVCCIN_CPU1
  BY61  VCCIN210  POWER  = PVCCIN_CPU1
  BY63  VCCIN211  POWER  = PVCCIN_CPU1
  BY65  VCCIN212  POWER  = PVCCIN_CPU1
  BY67  VCCIN213  POWER  = PVCCIN_CPU1
  BY69  VCCIN214  POWER  = PVCCIN_CPU1
  BY71  VCCIN215  POWER  = PVCCIN_CPU1
  BY73  VCCIN216  POWER  = PVCCIN_CPU1
  BY75  VCCIN217  POWER  = PVCCIN_CPU1
  BY77  VCCIN218  POWER  = PVCCIN_CPU1
  BY79  VCCIN219  POWER  = PVCCIN_CPU1
  BY81  VCCIN220  POWER  = PVCCIN_CPU1
  BY83  VCCIN221  POWER  = PVCCIN_CPU1
  BY85  VCCIN222  POWER  = PVCCIN_CPU1
  BY87  VCCIN223  POWER  = PVCCIN_CPU1
  BY89  VCCIN224  POWER  = PVCCIN_CPU1
  C5  VSS612  POWER  = GND
